G04 ================== begin FILE IDENTIFICATION RECORD ==================*
G04 Layout Name:  15126-1b.brd*
G04 Film Name:    P_OUTLINE*
G04 File Format:  Gerber RS274X*
G04 File Origin:  Cadence Allegro 16.6-2015-S079*
G04 Origin Date:  Fri Feb 10 17:21:43 2017*
G04 *
G04 Layer:  BOARD GEOMETRY/PANEL_OUTLINE*
G04 *
G04 Offset:    (0.00 0.00)*
G04 Mirror:    No*
G04 Mode:      Positive*
G04 Rotation:  0*
G04 FullContactRelief:  No*
G04 UndefLineWidth:     6.00*
G04 ================== end FILE IDENTIFICATION RECORD ====================*
%FSLAX35Y35*MOIN*%
%IR0*IPPOS*OFA0.00000B0.00000*MIA0B0*SFA1.00000B1.00000*%
%ADD10C,.006*%
G75*
%LPD*%
G75*
G54D10*
G01X-7874Y-31496D02*
X-19685D01*
G01X-7874D02*
X-19685D01*
G01D02*
G03X-23622Y-35433I0J-3937D01*
G01D02*
Y-59055D01*
G01Y-35433D02*
Y-59055D01*
G01X-19685Y-31496D02*
G03X-23622Y-35433I0J-3937D01*
G01Y-59055D02*
G03X-19685Y-62992I3937J0D01*
G01D02*
X1972441D01*
G01X-19685D02*
X1972441D01*
G01X-23622Y-59055D02*
G03X-19685Y-62992I3937J0D01*
G01Y-23622D02*
X1972441D01*
G01X-19685D02*
X1972441D01*
G01X-19685D02*
X1972441D01*
G01X-19685D02*
X1972441D01*
G01X-23622Y622441D02*
Y-19685D01*
G01Y622441D02*
Y-19685D01*
G01Y622441D02*
Y-19685D01*
G01Y622441D02*
Y-19685D01*
G01D02*
G03X-19685Y-23622I3937J0D01*
G01X-23622Y-19685D02*
G03X-19685Y-23622I3937J0D01*
G01X-23622Y-19685D02*
G03X-19685Y-23622I3937J0D01*
G01X-23622Y-19685D02*
G03X-19685Y-23622I3937J0D01*
G01X1972441Y626378D02*
X-19685D01*
G01X1972441D02*
X-19685D01*
G01X1972441D02*
X-19685D01*
G01X1972441D02*
X-19685D01*
G01D02*
G03X-23622Y622441I0J-3937D01*
G01X-19685Y626378D02*
G03X-23622Y622441I0J-3937D01*
G01X-19685Y626378D02*
G03X-23622Y622441I0J-3937D01*
G01X-19685Y626378D02*
G03X-23622Y622441I0J-3937D01*
G01X-19685Y634252D02*
X-7874D01*
G01X-19685D02*
X-7874D01*
G01X-23622Y661811D02*
Y638189D01*
G01Y661811D02*
Y638189D01*
G01D02*
G03X-19685Y634252I3937J0D01*
G01X-23622Y638189D02*
G03X-19685Y634252I3937J0D01*
G01X1972441Y665748D02*
X-19685D01*
G01X1972441D02*
X-19685D01*
G01D02*
G03X-23622Y661811I0J-3937D01*
G01X-19685Y665748D02*
G03X-23622Y661811I0J-3937D01*
G01X-7874Y-31496D02*
G03Y-23622I0J3937D01*
G01Y-31496D02*
G03Y-23622I0J3937D01*
G01X22835D02*
G03Y-31496I0J-3937D01*
G01X137795D02*
X22835D01*
G01X137795D02*
X22835D01*
G01Y-23622D02*
G03Y-31496I0J-3937D01*
G01X0Y616535D02*
G03Y604724I0J-5905D01*
G01Y616535D02*
G03Y604724I0J-5905D01*
G01Y616535D02*
X2646D01*
G01X2644D02*
X0D01*
G01Y604724D02*
X2644D01*
G01X2646D02*
X0D01*
G01X2646D02*
X0D01*
G01D02*
X2644D01*
G01Y616535D02*
X0D01*
G01D02*
X2646D01*
G01X0D02*
G03Y604724I0J-5905D01*
G01Y616535D02*
G03Y604724I0J-5905D01*
G01X2646Y616535D02*
G03X7595Y618285I0J7874D01*
G01X2644Y616535D02*
G03X7593Y618285I0J7874D01*
G01X2644Y616535D02*
G03X7593Y618285I0J7874D01*
G01X7595Y602975D02*
G03X2646Y604724I-4948J-6125D01*
G01X7593Y602975D02*
G03X2644Y604724I-4948J-6125D01*
G01X7593Y602975D02*
G03X2644Y604724I-4948J-6125D01*
G01X7593Y602975D02*
G03X2644Y604724I-4948J-6125D01*
G01X7593Y602975D02*
G03X2644Y604724I-4948J-6125D01*
G01X7595Y602975D02*
G03X2646Y604724I-4948J-6125D01*
G01X2644Y616535D02*
G03X7593Y618285I0J7874D01*
G01X2644Y616535D02*
G03X7593Y618285I0J7874D01*
G01X2646Y616535D02*
G03X7595Y618285I0J7874D01*
G01Y602975D02*
G03Y618285I6186J7655D01*
G01X7593Y602975D02*
G03Y618285I6187J7655D01*
G01Y602975D02*
G03Y618285I6187J7655D01*
G01Y602975D02*
G03Y618285I6187J7655D01*
G01Y602975D02*
G03Y618285I6187J7655D01*
G01X7595Y602975D02*
G03Y618285I6186J7655D01*
G01X-7874Y626378D02*
G03Y634252I0J3937D01*
G01Y626378D02*
G03Y634252I0J3937D01*
G01X22835D02*
G03Y626378I0J-3937D01*
G01Y634252D02*
X137795D01*
G01X22835D02*
X137795D01*
G01X22835D02*
G03Y626378I0J-3937D01*
G01X168504Y-23622D02*
G03Y-31496I0J-3937D01*
G01X137795D02*
G03Y-23622I0J3937D01*
G01X341732Y-31496D02*
X168504D01*
G01X341732D02*
X168504D01*
G01X137795D02*
G03Y-23622I0J3937D01*
G01X168504D02*
G03Y-31496I0J-3937D01*
G01Y634252D02*
G03Y626378I0J-3937D01*
G01X137795D02*
G03Y634252I0J3937D01*
G01X168504D02*
X341732D01*
G01X168504D02*
X341732D01*
G01X137795Y626378D02*
G03Y634252I0J3937D01*
G01X168504D02*
G03Y626378I0J-3937D01*
G01X341732Y-31496D02*
G03Y-23622I0J3937D01*
G01Y-31496D02*
G03Y-23622I0J3937D01*
G01Y626378D02*
G03Y634252I0J3937D01*
G01Y626378D02*
G03Y634252I0J3937D01*
G01X372441Y-23622D02*
G03Y-31496I0J-3937D01*
G01X529921D02*
X372441D01*
G01X529921D02*
X372441D01*
G01Y-23622D02*
G03Y-31496I0J-3937D01*
G01Y634252D02*
G03Y626378I0J-3937D01*
G01Y634252D02*
X529921D01*
G01X372441D02*
X529921D01*
G01X372441D02*
G03Y626378I0J-3937D01*
G01X529921Y-31496D02*
G03Y-23622I0J3937D01*
G01Y-31496D02*
G03Y-23622I0J3937D01*
G01Y626378D02*
G03Y634252I0J3937D01*
G01Y626378D02*
G03Y634252I0J3937D01*
G01X560630Y-23622D02*
G03Y-31496I0J-3937D01*
G01X788976D02*
X560630D01*
G01X788976D02*
X560630D01*
G01Y-23622D02*
G03Y-31496I0J-3937D01*
G01Y634252D02*
G03Y626378I0J-3937D01*
G01Y634252D02*
X788976D01*
G01X560630D02*
X788976D01*
G01X560630D02*
G03Y626378I0J-3937D01*
G01X684760Y-15529D02*
G03Y-219I6187J7655D01*
G01X684759Y-15529D02*
G03X679809Y-13780I-4948J-6125D01*
G01X679811Y-1969D02*
G03X684760Y-219I0J7874D01*
G01X677165Y-1969D02*
X679811D01*
G01X677165D02*
G03Y-13780I0J-5906D01*
G01D02*
X679809D01*
G01X684760Y602975D02*
G03Y618285I6187J7655D01*
G01X684759Y602975D02*
G03Y618285I6186J7655D01*
G01Y602975D02*
G03Y618285I6186J7655D01*
G01Y602975D02*
G03Y618285I6186J7655D01*
G01Y602975D02*
G03Y618285I6186J7655D01*
G01X684760Y602975D02*
G03Y618285I6187J7655D01*
G01X679811Y616535D02*
G03X684760Y618285I0J7874D01*
G01X679809Y616535D02*
G03X684759Y618285I0J7874D01*
G01X679809Y616535D02*
G03X684759Y618285I0J7874D01*
G01X684760Y602975D02*
G03X679811Y604724I-4948J-6125D01*
G01X684759Y602975D02*
G03X679809Y604724I-4948J-6125D01*
G01X684759Y602975D02*
G03X679809Y604724I-4948J-6125D01*
G01X684759Y602975D02*
G03X679809Y604724I-4948J-6125D01*
G01X684759Y602975D02*
G03X679809Y604724I-4948J-6125D01*
G01X684760Y602975D02*
G03X679811Y604724I-4948J-6125D01*
G01X679809Y616535D02*
G03X684759Y618285I0J7874D01*
G01X679809Y616535D02*
G03X684759Y618285I0J7874D01*
G01X679811Y616535D02*
G03X684760Y618285I0J7874D01*
G01X677165Y616535D02*
X679811D01*
G01X677165D02*
G03Y604724I0J-5905D01*
G01D02*
X679809D01*
G01X788976Y-31496D02*
G03Y-23622I0J3937D01*
G01Y-31496D02*
G03Y-23622I0J3937D01*
G01X819685D02*
G03Y-31496I0J-3937D01*
G01X975591D02*
X819685D01*
G01X975591D02*
X819685D01*
G01Y-23622D02*
G03Y-31496I0J-3937D01*
G01X788976Y626378D02*
G03Y634252I0J3937D01*
G01Y626378D02*
G03Y634252I0J3937D01*
G01X819685D02*
G03Y626378I0J-3937D01*
G01Y634252D02*
X975591D01*
G01X819685D02*
X975591D01*
G01X819685D02*
G03Y626378I0J-3937D01*
G01X975591Y-31496D02*
G03Y-23622I0J3937D01*
G01Y-31496D02*
G03Y-23622I0J3937D01*
G01X1006299D02*
G03Y-31496I0J-3937D01*
G01X1162205D02*
X1006299D01*
G01X1162205D02*
X1006299D01*
G01Y-23622D02*
G03Y-31496I0J-3937D01*
G01Y634252D02*
X1162205D01*
G01X1006299D02*
X1162205D01*
G01X975591Y626378D02*
G03Y634252I0J3937D01*
G01Y626378D02*
G03Y634252I0J3937D01*
G01X1006299D02*
G03Y626378I0J-3937D01*
G01Y634252D02*
G03Y626378I0J-3937D01*
G01X1162205Y-31496D02*
G03Y-23622I0J3937D01*
G01Y-31496D02*
G03Y-23622I0J3937D01*
G01X1192913D02*
G03Y-31496I0J-3937D01*
G01X1398425D02*
X1192913D01*
G01X1398425D02*
X1192913D01*
G01Y-23622D02*
G03Y-31496I0J-3937D01*
G01Y634252D02*
X1394488D01*
G01X1192913D02*
X1394488D01*
G01X1162205Y626378D02*
G03Y634252I0J3937D01*
G01Y626378D02*
G03Y634252I0J3937D01*
G01X1192913D02*
G03Y626378I0J-3937D01*
G01Y634252D02*
G03Y626378I0J-3937D01*
G01X1398425Y-31496D02*
G03Y-23622I0J3937D01*
G01Y-31496D02*
G03Y-23622I0J3937D01*
G01X1405512Y-1968D02*
G03Y-13779I0J-5906D01*
G01Y-1968D02*
G03Y-13779I0J-5906D01*
G01Y-1968D02*
G03Y-13779I0J-5906D01*
G01Y-1968D02*
G03Y-13779I0J-5906D01*
G01X1394488Y626378D02*
G03Y634252I0J3937D01*
G01Y626378D02*
G03Y634252I0J3937D01*
G01X1405512Y616535D02*
G03Y604724I0J-5905D01*
G01Y616535D02*
G03Y604724I0J-5905D01*
G01Y616535D02*
G03Y604724I0J-5905D01*
G01Y616535D02*
G03Y604724I0J-5905D01*
G01X1429134Y-23622D02*
G03Y-31496I0J-3937D01*
G01X1851181D02*
X1429134D01*
G01X1851181D02*
X1429134D01*
G01Y-23622D02*
G03Y-31496I0J-3937D01*
G01X1413107Y-15529D02*
G03Y-218I6186J7655D01*
G01X1413105Y-15529D02*
G03Y-218I6186J7655D01*
G01Y-15529D02*
G03Y-218I6186J7655D01*
G01Y-15529D02*
G03Y-218I6186J7655D01*
G01Y-15529D02*
G03Y-218I6186J7655D01*
G01X1413107Y-15529D02*
G03Y-218I6186J7655D01*
G01X1408157Y-1968D02*
G03X1413107Y-218I1J7874D01*
G01X1408156Y-1968D02*
G03X1413105Y-218I0J7874D01*
G01X1408156Y-1968D02*
G03X1413105Y-218I0J7874D01*
G01X1408156Y-1968D02*
G03X1413105Y-218I0J7874D01*
G01X1408156Y-1968D02*
G03X1413105Y-218I0J7874D01*
G01X1408157Y-1968D02*
G03X1413107Y-218I1J7874D01*
G01Y-15529D02*
G03X1408157Y-13779I-4949J-6124D01*
G01X1413105Y-15529D02*
G03X1408156Y-13779I-4949J-6124D01*
G01X1413105Y-15529D02*
G03X1408156Y-13779I-4949J-6124D01*
G01X1413105Y-15529D02*
G03X1408156Y-13779I-4949J-6124D01*
G01X1413105Y-15529D02*
G03X1408156Y-13779I-4949J-6124D01*
G01X1413107Y-15529D02*
G03X1408157Y-13779I-4949J-6124D01*
G01X1405512D02*
X1408156D01*
G01X1408157D02*
X1405512D01*
G01X1408157D02*
X1405512D01*
G01D02*
X1408156D01*
G01X1405512Y-1968D02*
X1408157D01*
G01X1408156D02*
X1405512D01*
G01X1408156D02*
X1405512D01*
G01D02*
X1408157D01*
G01X1425197Y634252D02*
X1851181D01*
G01X1425197D02*
X1851181D01*
G01X1425197D02*
G03Y626378I0J-3937D01*
G01Y634252D02*
G03Y626378I0J-3937D01*
G01X1408157Y616535D02*
G03X1413107Y618285I1J7874D01*
G01X1408156Y616535D02*
G03X1413105Y618285I0J7874D01*
G01X1408156Y616535D02*
G03X1413105Y618285I0J7874D01*
G01X1413107Y602975D02*
G03Y618285I6186J7655D01*
G01X1413105Y602975D02*
G03Y618285I6187J7655D01*
G01Y602975D02*
G03Y618285I6187J7655D01*
G01X1413107Y602975D02*
G03X1408157Y604724I-4948J-6125D01*
G01X1413105Y602975D02*
G03X1408156Y604724I-4948J-6125D01*
G01X1413105Y602975D02*
G03X1408156Y604724I-4948J-6125D01*
G01X1413105Y602975D02*
G03X1408156Y604724I-4948J-6125D01*
G01X1413105Y602975D02*
G03X1408156Y604724I-4948J-6125D01*
G01X1413107Y602975D02*
G03X1408157Y604724I-4948J-6125D01*
G01X1413105Y602975D02*
G03Y618285I6187J7655D01*
G01Y602975D02*
G03Y618285I6187J7655D01*
G01X1413107Y602975D02*
G03Y618285I6186J7655D01*
G01X1408156Y616535D02*
G03X1413105Y618285I0J7874D01*
G01X1408156Y616535D02*
G03X1413105Y618285I0J7874D01*
G01X1408157Y616535D02*
G03X1413107Y618285I1J7874D01*
G01X1405512Y616535D02*
X1408157D01*
G01X1408156D02*
X1405512D01*
G01Y604724D02*
X1408156D01*
G01X1408157D02*
X1405512D01*
G01X1408157D02*
X1405512D01*
G01D02*
X1408156D01*
G01Y616535D02*
X1405512D01*
G01D02*
X1408157D01*
G01X1685866Y267244D02*
X1883780D01*
G01X1685866D02*
X1883780D01*
G01X1685866D02*
X1883780D01*
G01X1685866D02*
X1883780D01*
G01X1681929Y271181D02*
G03X1685866Y267244I3937J0D01*
G01X1681929Y271181D02*
G03X1685866Y267244I3937J0D01*
G01X1681929Y271181D02*
G03X1685866Y267244I3937J0D01*
G01X1681929Y271181D02*
G03X1685866Y267244I3937J0D01*
G01X1681929Y428661D02*
Y271181D01*
G01Y428661D02*
Y271181D01*
G01Y428661D02*
Y271181D01*
G01Y428661D02*
Y271181D01*
G01X1685866Y432598D02*
G03X1681929Y428661I0J-3937D01*
G01X1685866Y432598D02*
G03X1681929Y428661I0J-3937D01*
G01X1972441Y432598D02*
X1685866D01*
G01X1972441D02*
X1685866D01*
G01X1972441D02*
X1685866D01*
G01X1972441D02*
X1685866D01*
G01D02*
G03X1681929Y428661I0J-3937D01*
G01X1685866Y432598D02*
G03X1681929Y428661I0J-3937D01*
G01X1851181Y-31496D02*
G03Y-23622I0J3937D01*
G01Y-31496D02*
G03Y-23622I0J3937D01*
G01X1881890D02*
G03Y-31496I0J-3937D01*
G01X1972441D02*
X1881890D01*
G01X1972441D02*
X1881890D01*
G01Y-23622D02*
G03Y-31496I0J-3937D01*
G01X1861926Y-15529D02*
G03X1856976Y-13780I-4948J-6125D01*
G01X1861924Y-15529D02*
G03X1856975Y-13780I-4948J-6125D01*
G01X1861924Y-15529D02*
G03X1856975Y-13780I-4948J-6125D01*
G01X1861924Y-15529D02*
G03X1856975Y-13780I-4948J-6125D01*
G01X1861924Y-15529D02*
G03X1856975Y-13780I-4948J-6125D01*
G01X1861926Y-15529D02*
G03X1856976Y-13780I-4948J-6125D01*
G01Y-1969D02*
G03X1861926Y-219I0J7874D01*
G01X1856975Y-1969D02*
G03X1861924Y-219I0J7874D01*
G01X1856975Y-1969D02*
G03X1861924Y-219I0J7874D01*
G01X1861926Y-15529D02*
G03Y-219I6186J7655D01*
G01X1861924Y-15529D02*
G03Y-219I6186J7655D01*
G01Y-15529D02*
G03Y-219I6186J7655D01*
G01Y-15529D02*
G03Y-219I6186J7655D01*
G01Y-15529D02*
G03Y-219I6186J7655D01*
G01X1861926Y-15529D02*
G03Y-219I6186J7655D01*
G01X1856975Y-1969D02*
G03X1861924Y-219I0J7874D01*
G01X1856975Y-1969D02*
G03X1861924Y-219I0J7874D01*
G01X1856976Y-1969D02*
G03X1861926Y-219I0J7874D01*
G01X1854331Y-1969D02*
G03Y-13780I0J-5906D01*
G01Y-1969D02*
G03Y-13780I0J-5906D01*
G01D02*
X1856975D01*
G01X1856976D02*
X1854331D01*
G01X1856976D02*
X1854331D01*
G01D02*
X1856975D01*
G01X1854331Y-1969D02*
G03Y-13780I0J-5906D01*
G01Y-1969D02*
G03Y-13780I0J-5906D01*
G01Y-1969D02*
X1856976D01*
G01X1856975D02*
X1854331D01*
G01X1856975D02*
X1854331D01*
G01D02*
X1856976D01*
G01X1891654Y246772D02*
X1972441D01*
G01X1891654D02*
X1972441D01*
G01X1891654D02*
X1972441D01*
G01X1891654D02*
X1972441D01*
G01X1887717Y250709D02*
G03X1891654Y246772I3937J0D01*
G01X1887717Y250709D02*
G03X1891654Y246772I3937J0D01*
G01X1887717Y263307D02*
Y250709D01*
G01Y263307D02*
Y250709D01*
G01Y263307D02*
Y250709D01*
G01Y263307D02*
Y250709D01*
G01D02*
G03X1891654Y246772I3937J0D01*
G01X1887717Y250709D02*
G03X1891654Y246772I3937J0D01*
G01X1887717Y263307D02*
G03X1883780Y267244I-3937J0D01*
G01X1887717Y263307D02*
G03X1883780Y267244I-3937J0D01*
G01X1887717Y263307D02*
G03X1883780Y267244I-3937J0D01*
G01X1887717Y263307D02*
G03X1883780Y267244I-3937J0D01*
G01X1881890Y634252D02*
G03Y626378I0J-3937D01*
G01Y634252D02*
X1972441D01*
G01X1881890D02*
X1972441D01*
G01X1881890D02*
G03Y626378I0J-3937D01*
G01X1851181D02*
G03Y634252I0J3937D01*
G01Y626378D02*
G03Y634252I0J3937D01*
G01X1856976Y616535D02*
G03X1861926Y618285I0J7874D01*
G01X1856975Y616535D02*
G03X1861924Y618285I0J7874D01*
G01X1856975Y616535D02*
G03X1861924Y618285I0J7874D01*
G01X1861926Y602975D02*
G03Y618285I6186J7655D01*
G01X1861924Y602975D02*
G03Y618285I6186J7655D01*
G01Y602975D02*
G03Y618285I6186J7655D01*
G01Y602975D02*
G03Y618285I6186J7655D01*
G01Y602975D02*
G03Y618285I6186J7655D01*
G01X1861926Y602975D02*
G03Y618285I6186J7655D01*
G01X1856975Y616535D02*
G03X1861924Y618285I0J7874D01*
G01X1856975Y616535D02*
G03X1861924Y618285I0J7874D01*
G01X1856976Y616535D02*
G03X1861926Y618285I0J7874D01*
G01Y602975D02*
G03X1856976Y604724I-4948J-6125D01*
G01X1861924Y602975D02*
G03X1856975Y604724I-4948J-6125D01*
G01X1861924Y602975D02*
G03X1856975Y604724I-4948J-6125D01*
G01X1861924Y602975D02*
G03X1856975Y604724I-4948J-6125D01*
G01X1861924Y602975D02*
G03X1856975Y604724I-4948J-6125D01*
G01X1861926Y602975D02*
G03X1856976Y604724I-4948J-6125D01*
G01X1854331Y616535D02*
G03Y604724I0J-5905D01*
G01Y616535D02*
G03Y604724I0J-5905D01*
G01D02*
X1856975D01*
G01X1856976D02*
X1854331D01*
G01X1856976D02*
X1854331D01*
G01D02*
X1856975D01*
G01X1854331Y616535D02*
G03Y604724I0J-5905D01*
G01Y616535D02*
G03Y604724I0J-5905D01*
G01Y616535D02*
X1856976D01*
G01X1856975D02*
X1854331D01*
G01X1856975D02*
X1854331D01*
G01D02*
X1856976D01*
G01X1972441Y-11811D02*
X1906890D01*
G01X1904921Y-9843D02*
G03X1906890Y-11811I1969J1D01*
G01X1904921Y53150D02*
Y-9843D01*
G01X1972441Y-11811D02*
X1906890D01*
G01X1904921Y-9843D02*
G03X1906890Y-11811I1969J1D01*
G01X1904921Y53150D02*
Y-9843D01*
G01X1923071Y53150D02*
Y-9843D01*
G01X1940787Y-3937D02*
X1972441D01*
G01X1940787D02*
G03X1938819Y-5906I0J-1968D01*
G01Y-9843D02*
Y-5906D01*
G01Y-9843D02*
G03X1940787Y-11811I1968J0D01*
G01X1921102D02*
G03X1923071Y-9843I0J1969D01*
G01X1906890Y55118D02*
G03X1904921Y53150I0J-1969D01*
G01X1972441Y55118D02*
X1906890D01*
G01X1972441D02*
X1906890D01*
G01X1972441D02*
X1906890D01*
G01X1972441D02*
X1906890D01*
G01D02*
G03X1904921Y53150I0J-1969D01*
G01X1923071D02*
G03X1921102Y55118I-1969J-1D01*
G01X1940787D02*
G03X1938819Y53150I0J-1968D01*
G01Y49213D02*
Y53150D01*
G01Y49213D02*
G03X1940787Y47244I1968J-1D01*
G01X1972441D02*
X1940787D01*
G01X1976378Y-35433D02*
G03X1972441Y-31496I-3937J0D01*
G01X1976378Y-59055D02*
Y-35433D01*
G01Y-59055D02*
Y-35433D01*
G01D02*
G03X1972441Y-31496I-3937J0D01*
G01Y-62992D02*
G03X1976378Y-59055I0J3937D01*
G01X1972441Y-62992D02*
G03X1976378Y-59055I0J3937D01*
G01X1972441Y-23622D02*
G03X1976378Y-19685I0J3937D01*
G01X1972441Y-23622D02*
G03X1976378Y-19685I0J3937D01*
G01X1972441Y-23622D02*
G03X1976378Y-19685I0J3937D01*
G01X1972441Y-23622D02*
G03X1976378Y-19685I0J3937D01*
G01D02*
Y-15748D01*
G01Y-19685D02*
Y-15748D01*
G01Y-19685D02*
Y-15748D01*
G01Y-19685D02*
Y-15748D01*
G01D02*
G03X1972441Y-11811I-3937J0D01*
G01X1976378Y-15748D02*
G03X1972441Y-11811I-3937J0D01*
G01X1976378Y-15748D02*
G03X1972441Y-11811I-3937J0D01*
G01X1976378Y-15748D02*
G03X1972441Y-11811I-3937J0D01*
G01X1976378Y0D02*
Y43307D01*
G01X1972441Y-3937D02*
G03X1976378Y0I0J3937D01*
G01X1972441Y55118D02*
G03X1976378Y59055I0J3937D01*
G01X1972441Y55118D02*
G03X1976378Y59055I0J3937D01*
G01X1972441Y55118D02*
G03X1976378Y59055I0J3937D01*
G01X1972441Y55118D02*
G03X1976378Y59055I0J3937D01*
G01D02*
Y242835D01*
G01Y59055D02*
Y242835D01*
G01Y59055D02*
Y242835D01*
G01Y59055D02*
Y242835D01*
G01Y43307D02*
G03X1972441Y47244I-3937J0D01*
G01X1976378Y242835D02*
G03X1972441Y246772I-3937J0D01*
G01X1976378Y242835D02*
G03X1972441Y246772I-3937J0D01*
G01X1976378Y242835D02*
G03X1972441Y246772I-3937J0D01*
G01X1976378Y242835D02*
G03X1972441Y246772I-3937J0D01*
G01Y432598D02*
G03X1976378Y436535I0J3937D01*
G01X1972441Y432598D02*
G03X1976378Y436535I0J3937D01*
G01X1972441Y432598D02*
G03X1976378Y436535I0J3937D01*
G01X1972441Y432598D02*
G03X1976378Y436535I0J3937D01*
G01D02*
Y622441D01*
G01Y436535D02*
Y622441D01*
G01Y436535D02*
Y622441D01*
G01Y436535D02*
Y622441D01*
G01D02*
G03X1972441Y626378I-3937J0D01*
G01X1976378Y622441D02*
G03X1972441Y626378I-3937J0D01*
G01X1976378Y622441D02*
G03X1972441Y626378I-3937J0D01*
G01X1976378Y622441D02*
G03X1972441Y626378I-3937J0D01*
G01Y634252D02*
G03X1976378Y638189I0J3937D01*
G01X1972441Y634252D02*
G03X1976378Y638189I0J3937D01*
G01D02*
Y661811D01*
G01Y638189D02*
Y661811D01*
G01D02*
G03X1972441Y665748I-3937J0D01*
G01X1976378Y661811D02*
G03X1972441Y665748I-3937J0D01*
M02*
